# T6G (Grand Teton) — schematic netlist excerpt (pin names and nets, part order shuffled) for the footprints in the layout excerpt that follows; sources: Cadence DE-HDL packaged netlist, KiCad conversion of 04192023_DAF0TMB3IC0_F0TG_MB_C_brd_V02_OCP.brd

PC118  Q_CAP  1UF 25V 10% X6S  pkg C0402  page 192 : A = PVDD_33_S5_VCC ; B = GND
PR6564  Q_RES  0 5% CHIP  pkg 0402LF  page 363 : A = P0V9_RETIMER_CPU0_VOS2 ; B = P0V9_CPU0_RT_2D

(kicad_pcb
	(version 20260206)
	(generator "pcbnew")
	(generator_version "10.0")
	(general
		(thickness 1.6)
		(legacy_teardrops no)
	)
	(paper "A4")
	(title_block
		(title "04192023_DAF0TMB3IC0_F0TG_MB_C_brd_V02_OCP.brd")
		(comment 1 "Grand Teton / footprints 2903-2904 of 8354")
	)
	(layers
		(0 "F.Cu" signal "TOP")
		(4 "In1.Cu" signal "GND")
		(6 "In2.Cu" signal "IN1")
		(8 "In3.Cu" signal "GND1")
		(10 "In4.Cu" signal "IN2")
		(12 "In5.Cu" signal "GND2")
		(14 "In6.Cu" signal "IN3")
		(16 "In7.Cu" signal "GND3")
		(18 "In8.Cu" signal "VCC")
		(20 "In9.Cu" signal "VCC1")
		(22 "In10.Cu" signal "GND4")
		(24 "In11.Cu" signal "IN4")
		(26 "In12.Cu" signal "GND5")
		(28 "In13.Cu" signal "IN5")
		(30 "In14.Cu" signal "GND6")
		(32 "In15.Cu" signal "IN6")
		(34 "In16.Cu" signal "GND7")
		(2 "B.Cu" signal "BOTTOM")
		(9 "F.Adhes" user "F.Adhesive")
		(11 "B.Adhes" user "B.Adhesive")
		(13 "F.Paste" user "Package Geometry/Pastemask Top")
		(15 "B.Paste" user "Package Geometry/Pastemask Bottom")
		(5 "F.SilkS" user "Ref Des/Silkscreen Top")
		(7 "B.SilkS" user "Ref Des/Silkscreen Bottom")
		(1 "F.Mask" user "Board Geometry/Soldermask Top")
		(3 "B.Mask" user "Board Geometry/Soldermask Bottom")
		(17 "Dwgs.User" user "User.Drawings")
		(19 "Cmts.User" user "User.Comments")
		(21 "Eco1.User" user "User.Eco1")
		(23 "Eco2.User" user "User.Eco2")
		(25 "Edge.Cuts" user "Board Geometry/Outline")
		(27 "Margin" user)
		(31 "F.CrtYd" user "Package Geometry/Place Bound Top")
		(29 "B.CrtYd" user "Package Geometry/Place Bound Bottom")
		(35 "F.Fab" user "Ref Des/Assembly Top")
		(33 "B.Fab" user "Ref Des/Assembly Bottom")
	)
	(footprint ""
		(layer "F.Cu")
		(at 450.082666 -400.78787 180)
		(property "Reference" "PR6564"
			(at 0 0 180)
			(layer "F.SilkS")
			(hide yes)
			(effects
				(font
					(size 1.27 1.27)
				)
			)
		)
		(property "Value" ""
			(at 0 0 180)
			(layer "F.Fab")
			(effects
				(font
					(size 1.27 1.27)
				)
			)
		)
		(duplicate_pad_numbers_are_jumpers no)
		(fp_line
			(start 0.7874 0.4064)
			(end -0.7874 0.4064)
			(stroke
				(width 0.1524)
				(type default)
			)
			(layer "F.SilkS")
		)
		(fp_line
			(start 0.7874 -0.4064)
			(end 0.7874 0.4064)
			(stroke
				(width 0.1524)
				(type default)
			)
			(layer "F.SilkS")
		)
		(fp_line
			(start -0.233934 -0.4064)
			(end 0.7874 -0.4064)
			(stroke
				(width 0.1524)
				(type default)
			)
			(layer "F.SilkS")
		)
		(fp_line
			(start -0.7874 0.4064)
			(end -0.7874 -0.07747)
			(stroke
				(width 0.1524)
				(type default)
			)
			(layer "F.SilkS")
		)
		(fp_line
			(start 0.67945 0.3048)
			(end 0.120396 0.3048)
			(stroke
				(width 0.1)
				(type default)
			)
			(layer "F.Fab")
		)
		(fp_line
			(start 0.67945 -0.3048)
			(end 0.67945 0.3048)
			(stroke
				(width 0.1)
				(type default)
			)
			(layer "F.Fab")
		)
		(fp_line
			(start 0.12065 -0.2794)
			(end 0.12065 -0.3048)
			(stroke
				(width 0.1)
				(type default)
			)
			(layer "F.Fab")
		)
		(fp_line
			(start 0.12065 -0.3048)
			(end 0.67945 -0.3048)
			(stroke
				(width 0.1)
				(type default)
			)
			(layer "F.Fab")
		)
		(fp_line
			(start 0.120396 0.3048)
			(end 0.120396 0.2794)
			(stroke
				(width 0.1)
				(type default)
			)
			(layer "F.Fab")
		)
		(fp_line
			(start 0.120396 0.2794)
			(end -0.12065 0.2794)
			(stroke
				(width 0.1)
				(type default)
			)
			(layer "F.Fab")
		)
		(fp_line
			(start -0.12065 0.3048)
			(end -0.67945 0.3048)
			(stroke
				(width 0.1)
				(type default)
			)
			(layer "F.Fab")
		)
		(fp_line
			(start -0.12065 0.2794)
			(end -0.12065 0.3048)
			(stroke
				(width 0.1)
				(type default)
			)
			(layer "F.Fab")
		)
		(fp_line
			(start -0.12065 -0.2794)
			(end 0.12065 -0.2794)
			(stroke
				(width 0.1)
				(type default)
			)
			(layer "F.Fab")
		)
		(fp_line
			(start -0.12065 -0.305054)
			(end -0.12065 -0.2794)
			(stroke
				(width 0.1)
				(type default)
			)
			(layer "F.Fab")
		)
		(fp_line
			(start -0.67945 0.3048)
			(end -0.67945 -0.305054)
			(stroke
				(width 0.1)
				(type default)
			)
			(layer "F.Fab")
		)
		(fp_line
			(start -0.67945 -0.305054)
			(end -0.12065 -0.305054)
			(stroke
				(width 0.1)
				(type default)
			)
			(layer "F.Fab")
		)
		(pad "1" smd circle
			(at -0.40005 0 180)
			(size 0 0)
			(layers "F.Cu" "F.Mask" "F.Paste")
			(net "P0V9_RETIMER_CPU0_VOS2")
		)
		(pad "2" smd circle
			(at 0.40005 0 180)
			(size 0 0)
			(layers "F.Cu" "F.Mask" "F.Paste")
			(net "P0V9_CPU0_RT_2D")
		)
	)
	(footprint ""
		(layer "F.Cu")
		(at 197.979538 -339.282024 90)
		(property "Reference" "PC118"
			(at 0 0 90)
			(layer "F.SilkS")
			(hide yes)
			(effects
				(font
					(size 1.27 1.27)
				)
			)
		)
		(property "Value" ""
			(at 0 0 90)
			(layer "F.Fab")
			(effects
				(font
					(size 1.27 1.27)
				)
			)
		)
		(duplicate_pad_numbers_are_jumpers no)
		(fp_line
			(start 0.7874 -0.4064)
			(end 0.7874 0.4064)
			(stroke
				(width 0.1524)
				(type default)
			)
			(layer "F.SilkS")
		)
		(fp_line
			(start -0.7874 -0.4064)
			(end 0.7874 -0.4064)
			(stroke
				(width 0.1524)
				(type default)
			)
			(layer "F.SilkS")
		)
		(fp_line
			(start 0.7874 0.4064)
			(end -0.7874 0.4064)
			(stroke
				(width 0.1524)
				(type default)
			)
			(layer "F.SilkS")
		)
		(fp_line
			(start -0.7874 0.4064)
			(end -0.7874 -0.4064)
			(stroke
				(width 0.1524)
				(type default)
			)
			(layer "F.SilkS")
		)
		(fp_line
			(start -0.12065 -0.305054)
			(end -0.12065 -0.2794)
			(stroke
				(width 0.1)
				(type default)
			)
			(layer "F.Fab")
		)
		(fp_line
			(start -0.67945 -0.305054)
			(end -0.12065 -0.305054)
			(stroke
				(width 0.1)
				(type default)
			)
			(layer "F.Fab")
		)
		(fp_line
			(start 0.67945 -0.3048)
			(end 0.67945 0.3048)
			(stroke
				(width 0.1)
				(type default)
			)
			(layer "F.Fab")
		)
		(fp_line
			(start 0.12065 -0.3048)
			(end 0.67945 -0.3048)
			(stroke
				(width 0.1)
				(type default)
			)
			(layer "F.Fab")
		)
		(fp_line
			(start 0.12065 -0.2794)
			(end 0.12065 -0.3048)
			(stroke
				(width 0.1)
				(type default)
			)
			(layer "F.Fab")
		)
		(fp_line
			(start -0.12065 -0.2794)
			(end 0.12065 -0.2794)
			(stroke
				(width 0.1)
				(type default)
			)
			(layer "F.Fab")
		)
		(fp_line
			(start 0.120396 0.2794)
			(end -0.12065 0.2794)
			(stroke
				(width 0.1)
				(type default)
			)
			(layer "F.Fab")
		)
		(fp_line
			(start -0.12065 0.2794)
			(end -0.12065 0.3048)
			(stroke
				(width 0.1)
				(type default)
			)
			(layer "F.Fab")
		)
		(fp_line
			(start 0.67945 0.3048)
			(end 0.120396 0.3048)
			(stroke
				(width 0.1)
				(type default)
			)
			(layer "F.Fab")
		)
		(fp_line
			(start 0.120396 0.3048)
			(end 0.120396 0.2794)
			(stroke
				(width 0.1)
				(type default)
			)
			(layer "F.Fab")
		)
		(fp_line
			(start -0.12065 0.3048)
			(end -0.67945 0.3048)
			(stroke
				(width 0.1)
				(type default)
			)
			(layer "F.Fab")
		)
		(fp_line
			(start -0.67945 0.3048)
			(end -0.67945 -0.305054)
			(stroke
				(width 0.1)
				(type default)
			)
			(layer "F.Fab")
		)
		(pad "1" smd circle
			(at -0.40005 0 90)
			(size 0 0)
			(layers "F.Cu" "F.Mask" "F.Paste")
			(net "PVDD_33_S5_VCC")
		)
		(pad "2" smd circle
			(at 0.40005 0 90)
			(size 0 0)
			(layers "F.Cu" "F.Mask" "F.Paste")
			(net "GND")
		)
	)
)
